FILE_TYPE = MULTI_PHYS_TABLE;
PART 'TTL1G126_A'
{=================================================================================================================================================================}
:PACK_TYPE | VALUE          | MATERIAL | PART_NUMBER      = EnvComp | PART_NUMBER  | JEDEC_TYPE      | CLASS | DESCRIPTION            | HEIGHT    | COMPONENT_TYPE| LPID   | SPEED_URL | Status |RPL| AML | Bus_Unit | Days ;
{=================================================================================================================================================================}
'SOT'      |  '74HC1G126'   |  'IC'    |  'A79322-001'(!) = 'YES;YES;UNK;UNK;ok;CIP' | 'A79322-001' | 'SSOP5_53_65MA' | 'IC'  | 'SINGLE BUFFER 3S OUT' | '.043 IN' | 'SMALLSMT' | '' | 'http://speed.intel.com:8081/speed/module/pdm/item/pdm_item_detail_direct.asp?item_cde=A79322-001&item_rev=01&url_param=unused' | 'Conditional' | 'NO' | '2' | 'SMO_IC' | '84' 
'SOT'      |  '74HC1G126'   |  'EMPTY' |  'A79322-001'(!) = 'YES;YES;UNK;UNK;ok;CIP' | 'A79322-001' | 'SSOP5_53_65MA' | 'IO'  | 'SINGLE BUFFER 3S OUT' | '.043 IN' | 'SMALLSMT' | '' | 'http://speed.intel.com:8081/speed/module/pdm/item/pdm_item_detail_direct.asp?item_cde=A79322-001&item_rev=01&url_param=unused' | 'Conditional' | 'NO' | '2' | 'SMO_IC' | '84' 
END_PART
END.
